(kicad_pcb
	(version 20260206)
	(generator "pcbnew")
	(generator_version "10.0")
	(general
		(thickness 1.6)
		(legacy_teardrops no)
	)
	(paper "A4")
	(title_block
		(title "Wiwynn_Tioga_Pass_MB.brd")
		(comment 1 "Tioga Pass / footprints 1616-1620 of 4770")
	)
	(layers
		(0 "F.Cu" signal "TOP")
		(4 "In1.Cu" signal "L2GND")
		(6 "In2.Cu" signal "L3")
		(8 "In3.Cu" signal "L4GND")
		(10 "In4.Cu" signal "L5")
		(12 "In5.Cu" signal "L6GND")
		(14 "In6.Cu" signal "L7VCC")
		(16 "In7.Cu" signal "L8VCC")
		(18 "In8.Cu" signal "L9GND")
		(20 "In9.Cu" signal "L10")
		(22 "In10.Cu" signal "L11GND")
		(24 "In11.Cu" signal "L12")
		(26 "In12.Cu" signal "L13GND")
		(2 "B.Cu" signal "BOTTOM")
		(9 "F.Adhes" user "F.Adhesive")
		(11 "B.Adhes" user "B.Adhesive")
		(13 "F.Paste" user "Package Geometry/Pastemask Top")
		(15 "B.Paste" user "Package Geometry/Pastemask Bottom")
		(5 "F.SilkS" user "Ref Des/Silkscreen Top")
		(7 "B.SilkS" user "Ref Des/Silkscreen Bottom")
		(1 "F.Mask" user "Board Geometry/Soldermask Top")
		(3 "B.Mask" user "Board Geometry/Soldermask Bottom")
		(17 "Dwgs.User" user "User.Drawings")
		(19 "Cmts.User" user "User.Comments")
		(21 "Eco1.User" user "User.Eco1")
		(23 "Eco2.User" user "User.Eco2")
		(25 "Edge.Cuts" user "Board Geometry/Outline")
		(27 "Margin" user)
		(31 "F.CrtYd" user "Package Geometry/Place Bound Top")
		(29 "B.CrtYd" user "Package Geometry/Place Bound Bottom")
		(35 "F.Fab" user "Ref Des/Assembly Top")
		(33 "B.Fab" user "Ref Des/Assembly Bottom")
	)
	(footprint ""
		(layer "F.Cu")
		(at 182.3466 -52.5907 -90)
		(property "Reference" "C4E18"
			(at 0 0 270)
			(layer "F.SilkS")
			(hide yes)
			(effects
				(font
					(size 1.27 1.27)
				)
			)
		)
		(property "Value" ""
			(at 0 0 270)
			(layer "F.Fab")
			(effects
				(font
					(size 1.27 1.27)
				)
			)
		)
		(duplicate_pad_numbers_are_jumpers no)
		(fp_poly
			(pts
				(xy 0.3048 -0.1016) (xy 0.3048 0.9906) (xy -0.3048 0.9906) (xy -0.3048 -0.1016)
			)
			(stroke
				(width 0)
				(type default)
			)
			(fill no)
			(layer "F.CrtYd")
		)
		(fp_line
			(start -0.3048 0.9906)
			(end 0.3048 0.9906)
			(stroke
				(width 0.1)
				(type default)
			)
			(layer "F.Fab")
		)
		(fp_line
			(start 0.3048 0.9906)
			(end 0.3048 -0.1016)
			(stroke
				(width 0.1)
				(type default)
			)
			(layer "F.Fab")
		)
		(fp_line
			(start -0.3048 -0.1016)
			(end -0.3048 0.9906)
			(stroke
				(width 0.1)
				(type default)
			)
			(layer "F.Fab")
		)
		(fp_line
			(start 0.3048 -0.1016)
			(end -0.3048 -0.1016)
			(stroke
				(width 0.1)
				(type default)
			)
			(layer "F.Fab")
		)
		(pad "1" smd rect
			(at 0 0 270)
			(size 0.508 0.508)
			(layers "F.Cu" "F.Mask" "F.Paste")
			(net "VR_PVCCIO_CPU1_PH1_BOOT")
		)
		(pad "2" smd rect
			(at 0 0.889 270)
			(size 0.508 0.508)
			(layers "F.Cu" "F.Mask" "F.Paste")
			(net "VR_PVCCIO_CPU1_PH1_PHASE")
		)
		(zone
			(layer "F.Cu")
			(hatch none 0.5)
			(connect_pads
				(clearance 0)
			)
			(min_thickness 0.25)
			(keepout
				(tracks not_allowed)
				(vias allowed)
				(pads allowed)
				(copperpour not_allowed)
				(footprints allowed)
			)
			(placement
				(enabled no)
				(sheetname "")
			)
			(fill
				(thermal_gap 0.5)
				(thermal_bridge_width 0.5)
				(island_removal_mode 0)
			)
			(polygon
				(pts
					(xy 181.7116 -52.8447) (xy 181.7116 -52.3367) (xy 182.0926 -52.3367) (xy 182.0926 -52.8447)
				)
			)
		)
		(zone
			(layer "F.Cu")
			(hatch none 0.5)
			(connect_pads
				(clearance 0)
			)
			(min_thickness 0.25)
			(keepout
				(tracks allowed)
				(vias not_allowed)
				(pads allowed)
				(copperpour not_allowed)
				(footprints allowed)
			)
			(placement
				(enabled no)
				(sheetname "")
			)
			(fill
				(thermal_gap 0.5)
				(thermal_bridge_width 0.5)
				(island_removal_mode 0)
			)
			(polygon
				(pts
					(xy 182.0926 -52.8447) (xy 182.0926 -52.3367) (xy 181.7116 -52.3367) (xy 181.7116 -52.8447)
				)
			)
		)
	)
	(footprint ""
		(layer "F.Cu")
		(at 336.9564 -20.5486)
		(property "Reference" "R7F36"
			(at -0.8382 -0.67818 0)
			(unlocked yes)
			(layer "F.SilkS")
			(effects
				(font
					(size 0.4064 0.254)
					(thickness 0.1524)
				)
				(justify left)
			)
		)
		(property "Value" ""
			(at 0 0 0)
			(layer "F.Fab")
			(effects
				(font
					(size 1.27 1.27)
				)
			)
		)
		(duplicate_pad_numbers_are_jumpers no)
		(fp_poly
			(pts
				(xy -0.2794 -0.1016) (xy 0.2794 -0.1016) (xy 0.2794 0.9906) (xy -0.2794 0.9906)
			)
			(stroke
				(width 0)
				(type default)
			)
			(fill no)
			(layer "F.CrtYd")
		)
		(fp_line
			(start -0.2794 -0.1016)
			(end -0.2794 0.9906)
			(stroke
				(width 0.1)
				(type default)
			)
			(layer "F.Fab")
		)
		(fp_line
			(start -0.2794 0.9906)
			(end 0.2794 0.9906)
			(stroke
				(width 0.1)
				(type default)
			)
			(layer "F.Fab")
		)
		(fp_line
			(start 0.2794 -0.1016)
			(end -0.2794 -0.1016)
			(stroke
				(width 0.1)
				(type default)
			)
			(layer "F.Fab")
		)
		(fp_line
			(start 0.2794 0.9906)
			(end 0.2794 -0.1016)
			(stroke
				(width 0.1)
				(type default)
			)
			(layer "F.Fab")
		)
		(pad "1" smd rect
			(at 0 0)
			(size 0.508 0.508)
			(layers "F.Cu" "F.Mask" "F.Paste")
			(net "P3V3_STBY")
		)
		(pad "2" smd rect
			(at 0 0.889)
			(size 0.508 0.508)
			(layers "F.Cu" "F.Mask" "F.Paste")
			(net "PWRGD_PVDDQ_ABC")
		)
		(zone
			(layer "F.Cu")
			(hatch none 0.5)
			(connect_pads
				(clearance 0)
			)
			(min_thickness 0.25)
			(keepout
				(tracks allowed)
				(vias not_allowed)
				(pads allowed)
				(copperpour not_allowed)
				(footprints allowed)
			)
			(placement
				(enabled no)
				(sheetname "")
			)
			(fill
				(thermal_gap 0.5)
				(thermal_bridge_width 0.5)
				(island_removal_mode 0)
			)
			(polygon
				(pts
					(xy 336.7024 -20.2946) (xy 337.2104 -20.2946) (xy 337.2104 -19.9136) (xy 336.7024 -19.9136)
				)
			)
		)
		(zone
			(layer "F.Cu")
			(hatch none 0.5)
			(connect_pads
				(clearance 0)
			)
			(min_thickness 0.25)
			(keepout
				(tracks not_allowed)
				(vias allowed)
				(pads allowed)
				(copperpour not_allowed)
				(footprints allowed)
			)
			(placement
				(enabled no)
				(sheetname "")
			)
			(fill
				(thermal_gap 0.5)
				(thermal_bridge_width 0.5)
				(island_removal_mode 0)
			)
			(polygon
				(pts
					(xy 336.7024 -19.9136) (xy 337.2104 -19.9136) (xy 337.2104 -20.2946) (xy 336.7024 -20.2946)
				)
			)
		)
	)
	(footprint ""
		(layer "F.Cu")
		(at 376.367548 -153.347928)
		(property "Reference" "EU7A3"
			(at 3.320288 -0.2032 90)
			(unlocked yes)
			(layer "F.SilkS")
			(effects
				(font
					(size 0.7874 0.5842)
					(thickness 0.1524)
				)
			)
		)
		(property "Value" ""
			(at 0 0 0)
			(layer "F.Fab")
			(effects
				(font
					(size 1.27 1.27)
				)
			)
		)
		(duplicate_pad_numbers_are_jumpers no)
		(fp_line
			(start -3.0099 -3.5052)
			(end 2.9718 -3.5052)
			(stroke
				(width 0.1524)
				(type default)
			)
			(layer "F.SilkS")
		)
		(fp_line
			(start -3.0099 3.429)
			(end -3.0099 -3.5052)
			(stroke
				(width 0.1524)
				(type default)
			)
			(layer "F.SilkS")
		)
		(fp_line
			(start 2.9718 -3.5052)
			(end 2.9718 3.429)
			(stroke
				(width 0.1524)
				(type default)
			)
			(layer "F.SilkS")
		)
		(fp_line
			(start 2.9718 3.429)
			(end -3.0099 3.429)
			(stroke
				(width 0.1524)
				(type default)
			)
			(layer "F.SilkS")
		)
		(fp_circle
			(center -3.057398 -2.678684)
			(end -2.930398 -2.678684)
			(stroke
				(width 0.254)
				(type default)
			)
			(fill no)
			(layer "F.SilkS")
		)
		(fp_poly
			(pts
				(xy -2.9972 -3.4925) (xy -2.9972 -2.6924) (xy -2.1971 -3.4925)
			)
			(stroke
				(width 0)
				(type default)
			)
			(fill yes)
			(layer "F.SilkS")
		)
		(fp_poly
			(pts
				(xy -2.549906 -3.050032) (xy -2.549906 3.050032) (xy 2.549906 3.050032) (xy 2.549906 -3.050032)
			)
			(stroke
				(width 0)
				(type default)
			)
			(fill no)
			(layer "F.CrtYd")
		)
		(fp_line
			(start -2.549906 -3.050032)
			(end 2.549906 -3.050032)
			(stroke
				(width 0.1)
				(type default)
			)
			(layer "F.Fab")
		)
		(fp_line
			(start -2.549906 3.050032)
			(end -2.549906 -3.050032)
			(stroke
				(width 0.1)
				(type default)
			)
			(layer "F.Fab")
		)
		(fp_line
			(start 2.549906 -3.050032)
			(end 2.549906 3.050032)
			(stroke
				(width 0.1)
				(type default)
			)
			(layer "F.Fab")
		)
		(fp_line
			(start 2.549906 3.050032)
			(end -2.549906 3.050032)
			(stroke
				(width 0.1)
				(type default)
			)
			(layer "F.Fab")
		)
		(fp_circle
			(center -3.057398 -2.678684)
			(end -2.930398 -2.678684)
			(stroke
				(width 0.254)
				(type default)
			)
			(fill no)
			(layer "F.Fab")
		)
		(pad "1" smd rect
			(at -2.39522 -2.279904)
			(size 0.7112 0.254)
			(layers "F.Cu" "F.Mask" "F.Paste")
			(net "PVNN_PCH_STBY")
		)
		(pad "2" smd rect
			(at -2.39522 -1.83007)
			(size 0.7112 0.254)
			(layers "F.Cu" "F.Mask" "F.Paste")
			(net "GND")
		)
		(pad "3" smd rect
			(at -2.39522 -1.379982)
			(size 0.7112 0.254)
			(layers "F.Cu" "F.Mask" "F.Paste")
			(net "VR_PVNN_PCH_PH1_VCIN")
		)
		(pad "4" smd rect
			(at -2.39522 -0.929894)
			(size 0.7112 0.254)
			(layers "F.Cu" "F.Mask" "F.Paste")
			(net "P5V_STBY")
		)
		(pad "5" smd rect
			(at -2.39522 -0.48006)
			(size 0.7112 0.254)
			(layers "F.Cu" "F.Mask" "F.Paste")
			(net "GND")
		)
		(pad "6" smd rect
			(at -2.39522 -0.029972)
			(size 0.7112 0.254)
			(layers "F.Cu" "F.Mask" "F.Paste")
			(net "TP_PVNN_PCH_GL_0")
		)
		(pad "7" smd custom
			(at 0.016764 1.145032)
			(size 0.53975 0.53975)
			(layers "F.Cu" "F.Mask" "F.Paste")
			(net "GND")
			(options
				(clearance outline)
				(anchor circle)
			)
			(primitives
				(gr_poly
					(pts
						(xy -2.7051 1.0795) (xy -2.7051 -0.3683) (xy -0.9271 -0.3683) (xy -0.9271 -1.0795) (xy 2.7051 -1.0795)
						(xy 2.7051 1.0795)
					)
					(width 0)
					(fill yes)
				)
			)
		)
		(pad "10" smd rect
			(at -0.008382 2.874772)
			(size 4.3434 0.6096)
			(layers "F.Cu" "F.Mask" "F.Paste")
			(net "VR_PVNN_PCH_PH1_PHASE_SW")
		)
		(pad "25" smd rect
			(at 1.548384 -1.283208)
			(size 2.3368 2.0066)
			(layers "F.Cu" "F.Mask" "F.Paste")
			(net "VR_FET_SW_P12V_STBY_PVDDQ_DEF")
		)
		(pad "30" smd rect
			(at 2.050034 -2.895092)
			(size 0.254 0.7112)
			(layers "F.Cu" "F.Mask" "F.Paste")
			(net "VR_FET_SW_P12V_STBY_PVDDQ_DEF")
		)
		(pad "31" smd rect
			(at 1.599946 -2.895092)
			(size 0.254 0.7112)
			(layers "F.Cu" "F.Mask" "F.Paste")
			(net "Net_374")
		)
		(pad "32" smd rect
			(at 1.150112 -2.895092)
			(size 0.254 0.7112)
			(layers "F.Cu" "F.Mask" "F.Paste")
			(net "VR_PVNN_PCH_PH1_PHASE")
		)
		(pad "33" smd rect
			(at 0.700024 -2.895092)
			(size 0.254 0.7112)
			(layers "F.Cu" "F.Mask" "F.Paste")
			(net "VR_PVNN_PCH_PH1_BOOT_R")
		)
		(pad "34" smd rect
			(at 0.249936 -2.895092)
			(size 0.254 0.7112)
			(layers "F.Cu" "F.Mask" "F.Paste")
			(net "VR_PVNN_PCH_PWM1")
		)
		(pad "35" smd rect
			(at -0.199898 -2.895092)
			(size 0.254 0.7112)
			(layers "F.Cu" "F.Mask" "F.Paste")
			(net "P5V_STBY")
		)
		(pad "36" smd rect
			(at -0.649986 -2.895092)
			(size 0.254 0.7112)
			(layers "F.Cu" "F.Mask" "F.Paste")
			(net "A_TSENSE_PVNN_PCH_TMON")
		)
		(pad "37" smd rect
			(at -1.100074 -2.895092)
			(size 0.254 0.7112)
			(layers "F.Cu" "F.Mask" "F.Paste")
			(net "VR_PVNN_PCH_STBY_OCSET")
		)
		(pad "38" smd rect
			(at -1.549908 -2.895092)
			(size 0.254 0.7112)
			(layers "F.Cu" "F.Mask" "F.Paste")
			(net "ISENSE_PVNN_PCH_PH1_IMON")
		)
		(pad "39" smd rect
			(at -1.999996 -2.895092)
			(size 0.254 0.7112)
			(layers "F.Cu" "F.Mask" "F.Paste")
			(net "VR_PVNN_PCH_AIREF1")
		)
		(pad "40" smd rect
			(at -0.871728 -1.283208)
			(size 1.8034 2.0066)
			(layers "F.Cu" "F.Mask" "F.Paste")
			(net "GND")
		)
		(pad "41" smd rect
			(at -1.533906 0.247904)
			(size 0.508 0.3556)
			(layers "F.Cu" "F.Mask" "F.Paste")
			(net "TP_PVNN_PCH_GL_1")
		)
	)
	(footprint ""
		(layer "F.Cu")
		(at 413.4612 -117.8814 180)
		(property "Reference" "R8B21"
			(at 0 0 180)
			(layer "F.SilkS")
			(hide yes)
			(effects
				(font
					(size 1.27 1.27)
				)
			)
		)
		(property "Value" ""
			(at 0 0 180)
			(layer "F.Fab")
			(effects
				(font
					(size 1.27 1.27)
				)
			)
		)
		(duplicate_pad_numbers_are_jumpers no)
		(fp_poly
			(pts
				(xy -0.2794 -0.1016) (xy 0.2794 -0.1016) (xy 0.2794 0.9906) (xy -0.2794 0.9906)
			)
			(stroke
				(width 0)
				(type default)
			)
			(fill no)
			(layer "F.CrtYd")
		)
		(fp_line
			(start 0.2794 0.9906)
			(end 0.2794 -0.1016)
			(stroke
				(width 0.1)
				(type default)
			)
			(layer "F.Fab")
		)
		(fp_line
			(start 0.2794 -0.1016)
			(end -0.2794 -0.1016)
			(stroke
				(width 0.1)
				(type default)
			)
			(layer "F.Fab")
		)
		(fp_line
			(start -0.2794 0.9906)
			(end 0.2794 0.9906)
			(stroke
				(width 0.1)
				(type default)
			)
			(layer "F.Fab")
		)
		(fp_line
			(start -0.2794 -0.1016)
			(end -0.2794 0.9906)
			(stroke
				(width 0.1)
				(type default)
			)
			(layer "F.Fab")
		)
		(pad "1" smd rect
			(at 0 0 180)
			(size 0.508 0.508)
			(layers "F.Cu" "F.Mask" "F.Paste")
			(net "H_PMSYNC_CLK_24M")
		)
		(pad "2" smd rect
			(at 0 0.889 180)
			(size 0.508 0.508)
			(layers "F.Cu" "F.Mask" "F.Paste")
			(net "GND")
		)
		(zone
			(layer "F.Cu")
			(hatch none 0.5)
			(connect_pads
				(clearance 0)
			)
			(min_thickness 0.25)
			(keepout
				(tracks not_allowed)
				(vias allowed)
				(pads allowed)
				(copperpour not_allowed)
				(footprints allowed)
			)
			(placement
				(enabled no)
				(sheetname "")
			)
			(fill
				(thermal_gap 0.5)
				(thermal_bridge_width 0.5)
				(island_removal_mode 0)
			)
			(polygon
				(pts
					(xy 413.7152 -118.5164) (xy 413.2072 -118.5164) (xy 413.2072 -118.1354) (xy 413.7152 -118.1354)
				)
			)
		)
		(zone
			(layer "F.Cu")
			(hatch none 0.5)
			(connect_pads
				(clearance 0)
			)
			(min_thickness 0.25)
			(keepout
				(tracks allowed)
				(vias not_allowed)
				(pads allowed)
				(copperpour not_allowed)
				(footprints allowed)
			)
			(placement
				(enabled no)
				(sheetname "")
			)
			(fill
				(thermal_gap 0.5)
				(thermal_bridge_width 0.5)
				(island_removal_mode 0)
			)
			(polygon
				(pts
					(xy 413.7152 -118.1354) (xy 413.2072 -118.1354) (xy 413.2072 -118.5164) (xy 413.7152 -118.5164)
				)
			)
		)
	)
	(footprint ""
		(layer "F.Cu")
		(at 470.2175 -142.494 180)
		(property "Reference" "J9A1"
			(at -2.29362 -1.86055 0)
			(unlocked yes)
			(layer "B.SilkS")
			(effects
				(font
					(size 0.7874 0.5842)
					(thickness 0.1524)
				)
				(justify left mirror)
			)
		)
		(property "Value" ""
			(at 0 0 180)
			(layer "F.Fab")
			(effects
				(font
					(size 1.27 1.27)
				)
			)
		)
		(duplicate_pad_numbers_are_jumpers no)
		(fp_line
			(start 2.153412 8.64997)
			(end -1.746504 8.64997)
			(stroke
				(width 0.1524)
				(type default)
			)
			(layer "F.SilkS")
		)
		(fp_line
			(start 2.153412 -2.649982)
			(end 2.153412 8.64997)
			(stroke
				(width 0.1524)
				(type default)
			)
			(layer "F.SilkS")
		)
		(fp_line
			(start -1.746504 8.64997)
			(end -1.746504 -2.649982)
			(stroke
				(width 0.1524)
				(type default)
			)
			(layer "F.SilkS")
		)
		(fp_line
			(start -1.746504 -2.649982)
			(end 2.153412 -2.649982)
			(stroke
				(width 0.1524)
				(type default)
			)
			(layer "F.SilkS")
		)
		(fp_poly
			(pts
				(xy -3.664204 -0.499618) (xy -3.664204 0.516382) (xy -2.394204 0.008382)
			)
			(stroke
				(width 0)
				(type default)
			)
			(fill yes)
			(layer "F.SilkS")
		)
		(fp_poly
			(pts
				(xy 1.950974 0.512064) (xy 1.950974 -0.503936) (xy 0.680974 0.004064)
			)
			(stroke
				(width 0)
				(type default)
			)
			(fill yes)
			(layer "B.SilkS")
		)
		(fp_poly
			(pts
				(xy -1.746504 -2.649982) (xy -1.746504 8.64997) (xy 2.153412 8.64997) (xy 2.153412 -2.649982)
			)
			(stroke
				(width 0)
				(type default)
			)
			(fill no)
			(layer "F.CrtYd")
		)
		(fp_poly
			(pts
				(xy -3.664204 -0.499618) (xy -3.664204 0.516382) (xy -2.394204 0.008382)
			)
			(stroke
				(width 0)
				(type default)
			)
			(fill yes)
			(layer "B.Fab")
		)
		(fp_line
			(start 2.153412 8.64997)
			(end -1.746504 8.64997)
			(stroke
				(width 0.1)
				(type default)
			)
			(layer "F.Fab")
		)
		(fp_line
			(start 2.153412 -2.649982)
			(end 2.153412 8.64997)
			(stroke
				(width 0.1)
				(type default)
			)
			(layer "F.Fab")
		)
		(fp_line
			(start -1.746504 8.64997)
			(end -1.746504 -2.649982)
			(stroke
				(width 0.1)
				(type default)
			)
			(layer "F.Fab")
		)
		(fp_line
			(start -1.746504 -2.649982)
			(end 2.153412 -2.649982)
			(stroke
				(width 0.1)
				(type default)
			)
			(layer "F.Fab")
		)
		(fp_poly
			(pts
				(xy -3.664204 -0.499618) (xy -3.664204 0.516382) (xy -2.394204 0.008382)
			)
			(stroke
				(width 0)
				(type default)
			)
			(fill yes)
			(layer "F.Fab")
		)
		(fp_text user "4"
			(at 0.7493 9.21893 0)
			(unlocked yes)
			(layer "F.SilkS")
			(effects
				(font
					(size 0.7874 0.5842)
					(thickness 0.1524)
				)
				(justify left)
			)
		)
		(fp_text user "4"
			(at -2.218436 6.033516 180)
			(unlocked yes)
			(layer "B.SilkS")
			(effects
				(font
					(size 0.7874 0.5842)
					(thickness 0.1524)
				)
				(justify left mirror)
			)
		)
		(fp_text user "4"
			(at -2.218436 6.033516 180)
			(unlocked yes)
			(layer "B.Fab")
			(effects
				(font
					(size 0.7874 0.5842)
					(thickness 0.1524)
				)
				(justify left mirror)
			)
		)
		(fp_text user "4"
			(at 2.962402 8.50265 0)
			(unlocked yes)
			(layer "F.Fab")
			(effects
				(font
					(size 0.7874 0.5842)
					(thickness 0.1524)
				)
				(justify left)
			)
		)
		(pad "1" thru_hole rect
			(at 0 0 180)
			(size 1.1938 1.1938)
			(drill 0.8128)
			(layers "*.Cu" "*.Mask")
			(remove_unused_layers no)
			(net "GND")
			(clearance 0.127)
			(thermal_gap 0.127)
			(padstack
				(mode front_inner_back)
				(layer "Inner"
					(shape circle)
					(size 1.1938 1.1938)
					(clearance 0.127)
				)
				(layer "B.Cu"
					(shape rect)
					(size 1.1938 1.1938)
					(clearance 0.127)
				)
			)
		)
		(pad "2" thru_hole circle
			(at 0 1.999996 180)
			(size 1.1938 1.1938)
			(drill 0.8128)
			(layers "*.Cu" "*.Mask")
			(remove_unused_layers no)
			(net "PU_KEY_CONN_PIN2_R")
			(clearance 0.127)
			(thermal_gap 0.127)
		)
		(pad "3" thru_hole circle
			(at 0 3.999992 180)
			(size 1.1938 1.1938)
			(drill 0.8128)
			(layers "*.Cu" "*.Mask")
			(remove_unused_layers no)
			(net "GND")
			(clearance 0.127)
			(thermal_gap 0.127)
		)
		(pad "4" thru_hole circle
			(at 0 5.999988 180)
			(size 1.1938 1.1938)
			(drill 0.8128)
			(layers "*.Cu" "*.Mask")
			(remove_unused_layers no)
			(net "FM_PCH_SATA_RAID_KEY_R")
			(clearance 0.127)
			(thermal_gap 0.127)
		)
	)
)
